(kicad_pcb
	(version 20260206)
	(generator "pcbnew")
	(generator_version "10.0")
	(general
		(thickness 1.6)
		(legacy_teardrops no)
	)
	(paper "A4")
	(title_block
		(title "v1-pdb — T6M_PDB_D_0927_0900.brd")
		(comment 1 "Open CloudServer (Microsoft) / footprints 252-257 of 321")
	)
	(layers
		(0 "F.Cu" signal "TOP")
		(4 "In1.Cu" signal "GND")
		(6 "In2.Cu" signal "IN1")
		(8 "In3.Cu" signal "VCC")
		(10 "In4.Cu" signal "VCC1")
		(12 "In5.Cu" signal "IN2")
		(14 "In6.Cu" signal "GND1")
		(2 "B.Cu" signal "BOTTOM")
		(9 "F.Adhes" user "F.Adhesive")
		(11 "B.Adhes" user "B.Adhesive")
		(13 "F.Paste" user "Package Geometry/Pastemask Top")
		(15 "B.Paste" user "Package Geometry/Pastemask Bottom")
		(5 "F.SilkS" user "Ref Des/Silkscreen Top")
		(7 "B.SilkS" user "Ref Des/Silkscreen Bottom")
		(1 "F.Mask" user "Board Geometry/Soldermask Top")
		(3 "B.Mask" user "Board Geometry/Soldermask Bottom")
		(17 "Dwgs.User" user "User.Drawings")
		(19 "Cmts.User" user "User.Comments")
		(21 "Eco1.User" user "User.Eco1")
		(23 "Eco2.User" user "User.Eco2")
		(25 "Edge.Cuts" user "Board Geometry/Outline")
		(27 "Margin" user)
		(31 "F.CrtYd" user "Package Geometry/Place Bound Top")
		(29 "B.CrtYd" user "Package Geometry/Place Bound Bottom")
		(35 "F.Fab" user "Ref Des/Assembly Top")
		(33 "B.Fab" user "Ref Des/Assembly Bottom")
	)
	(footprint ""
		(layer "F.Cu")
		(at 4.50469 -521.121894)
		(property "Reference" "J24"
			(at 4.5085 14.04239 0)
			(unlocked yes)
			(layer "F.SilkS")
			(effects
				(font
					(size 0.7874 0.5842)
					(thickness 0.1524)
				)
				(justify left)
			)
		)
		(property "Value" ""
			(at 0 0 0)
			(layer "F.Fab")
			(effects
				(font
					(size 1.27 1.27)
				)
			)
		)
		(duplicate_pad_numbers_are_jumpers no)
		(fp_line
			(start -3.370072 -3.81)
			(end 12.260072 -3.81)
			(stroke
				(width 0.1524)
				(type default)
			)
			(layer "F.SilkS")
		)
		(fp_line
			(start -3.370072 12.830048)
			(end -3.370072 -3.81)
			(stroke
				(width 0.1524)
				(type default)
			)
			(layer "F.SilkS")
		)
		(fp_line
			(start 12.260072 -3.81)
			(end 12.260072 12.830048)
			(stroke
				(width 0.1524)
				(type default)
			)
			(layer "F.SilkS")
		)
		(fp_line
			(start 12.260072 12.830048)
			(end -3.370072 12.830048)
			(stroke
				(width 0.1524)
				(type default)
			)
			(layer "F.SilkS")
		)
		(fp_poly
			(pts
				(xy -3.48234 1.034034) (xy -3.700018 1.828038) (xy -4.24815 1.336294)
			)
			(stroke
				(width 0)
				(type default)
			)
			(fill yes)
			(layer "F.SilkS")
		)
		(fp_poly
			(pts
				(xy -0.762 0.762) (xy 8.382 0.762) (xy 8.382 -1.8034) (xy 9.652 -1.8034) (xy 9.652 -3.302) (xy 0.508 -3.302)
				(xy 0.508 -0.762) (xy -0.762 -0.762)
			)
			(stroke
				(width 0)
				(type default)
			)
			(fill no)
			(layer "B.CrtYd")
		)
		(fp_poly
			(pts
				(arc
					(start 0.6604 6.35)
					(mid -3.2004 6.35)
					(end 0.6604 6.35)
				)
			)
			(stroke
				(width 0)
				(type default)
			)
			(fill no)
			(layer "B.CrtYd")
		)
		(fp_poly
			(pts
				(arc
					(start 12.0904 6.35)
					(mid 8.2296 6.35)
					(end 12.0904 6.35)
				)
			)
			(stroke
				(width 0)
				(type default)
			)
			(fill no)
			(layer "B.CrtYd")
		)
		(fp_poly
			(pts
				(xy -3.370072 12.830048) (xy 12.260072 12.830048) (xy 12.260072 -3.81) (xy -3.370072 -3.81)
			)
			(stroke
				(width 0)
				(type default)
			)
			(fill no)
			(layer "F.CrtYd")
		)
		(fp_line
			(start -3.370072 -3.81)
			(end 12.260072 -3.81)
			(stroke
				(width 0.1)
				(type default)
			)
			(layer "F.Fab")
		)
		(fp_line
			(start -3.370072 12.830048)
			(end -3.370072 -3.81)
			(stroke
				(width 0.1)
				(type default)
			)
			(layer "F.Fab")
		)
		(fp_line
			(start 12.260072 -3.81)
			(end 12.260072 12.830048)
			(stroke
				(width 0.1)
				(type default)
			)
			(layer "F.Fab")
		)
		(fp_line
			(start 12.260072 12.830048)
			(end -3.370072 12.830048)
			(stroke
				(width 0.1)
				(type default)
			)
			(layer "F.Fab")
		)
		(fp_poly
			(pts
				(xy -3.576828 0) (xy -5.0038 0.713486) (xy -5.0038 -0.713486)
			)
			(stroke
				(width 0)
				(type default)
			)
			(fill yes)
			(layer "F.Fab")
		)
		(fp_text user "2"
			(at -3.9624 -2.428748 0)
			(unlocked yes)
			(layer "F.SilkS")
			(effects
				(font
					(size 0.7874 0.5842)
					(thickness 0.1524)
				)
			)
		)
		(fp_text user "1"
			(at -3.77952 -0.862584 0)
			(unlocked yes)
			(layer "F.SilkS")
			(effects
				(font
					(size 0.7874 0.5842)
					(thickness 0.1524)
				)
			)
		)
		(fp_text user "8"
			(at 12.7762 -2.555748 0)
			(unlocked yes)
			(layer "F.SilkS")
			(effects
				(font
					(size 0.7874 0.5842)
					(thickness 0.1524)
				)
			)
		)
		(fp_text user "7"
			(at 12.7762 -0.091948 0)
			(unlocked yes)
			(layer "F.SilkS")
			(effects
				(font
					(size 0.7874 0.5842)
					(thickness 0.1524)
				)
			)
		)
		(fp_text user "1"
			(at -1.2954 0.085852 0)
			(unlocked yes)
			(layer "B.SilkS")
			(effects
				(font
					(size 0.7874 0.5842)
					(thickness 0.1524)
				)
				(justify mirror)
			)
		)
		(fp_text user "2"
			(at 0 -2.581148 0)
			(unlocked yes)
			(layer "B.SilkS")
			(effects
				(font
					(size 0.7874 0.5842)
					(thickness 0.1524)
				)
				(justify mirror)
			)
		)
		(fp_text user "7"
			(at 8.8138 0.238252 0)
			(unlocked yes)
			(layer "B.SilkS")
			(effects
				(font
					(size 0.7874 0.5842)
					(thickness 0.1524)
				)
				(justify mirror)
			)
		)
		(fp_text user "8"
			(at 10.0838 -2.403348 0)
			(unlocked yes)
			(layer "B.SilkS")
			(effects
				(font
					(size 0.7874 0.5842)
					(thickness 0.1524)
				)
				(justify mirror)
			)
		)
		(fp_text user "1"
			(at -1.2954 0.085852 0)
			(unlocked yes)
			(layer "B.Fab")
			(effects
				(font
					(size 0.7874 0.5842)
					(thickness 0.000001)
				)
				(justify mirror)
			)
		)
		(fp_text user "2"
			(at 0 -2.581148 0)
			(unlocked yes)
			(layer "B.Fab")
			(effects
				(font
					(size 0.7874 0.5842)
					(thickness 0.000001)
				)
				(justify mirror)
			)
		)
		(fp_text user "7"
			(at 8.8138 0.238252 0)
			(unlocked yes)
			(layer "B.Fab")
			(effects
				(font
					(size 0.7874 0.5842)
					(thickness 0.000001)
				)
				(justify mirror)
			)
		)
		(fp_text user "8"
			(at 10.0838 -2.403348 0)
			(unlocked yes)
			(layer "B.Fab")
			(effects
				(font
					(size 0.7874 0.5842)
					(thickness 0.000001)
				)
				(justify mirror)
			)
		)
		(fp_text user "2"
			(at -3.9624 -2.428748 0)
			(unlocked yes)
			(layer "F.Fab")
			(effects
				(font
					(size 0.7874 0.5842)
					(thickness 0.000001)
				)
			)
		)
		(fp_text user "1"
			(at -3.9116 -0.930148 0)
			(unlocked yes)
			(layer "F.Fab")
			(effects
				(font
					(size 0.7874 0.5842)
					(thickness 0.000001)
				)
			)
		)
		(fp_text user "8"
			(at 12.7762 -2.555748 0)
			(unlocked yes)
			(layer "F.Fab")
			(effects
				(font
					(size 0.7874 0.5842)
					(thickness 0.000001)
				)
			)
		)
		(fp_text user "7"
			(at 12.7762 -0.091948 0)
			(unlocked yes)
			(layer "F.Fab")
			(effects
				(font
					(size 0.7874 0.5842)
					(thickness 0.000001)
				)
			)
		)
		(pad "" np_thru_hole circle
			(at -1.27 6.35)
			(size 3.3528 3.3528)
			(drill 3.3528)
			(layers "*.Cu" "*.Mask")
			(clearance 0.381)
			(thermal_gap 0.381)
		)
		(pad "" np_thru_hole circle
			(at 10.16 6.35)
			(size 3.3528 3.3528)
			(drill 3.3528)
			(layers "*.Cu" "*.Mask")
			(clearance 0.381)
			(thermal_gap 0.381)
		)
		(pad "1" thru_hole rect
			(at 0 0)
			(size 1.397 1.397)
			(drill 0.9906)
			(layers "*.Cu" "*.Mask")
			(remove_unused_layers no)
			(net "UART_RTS_RP6_L_N")
			(clearance 0.0508)
			(thermal_gap 0.0508)
			(padstack
				(mode front_inner_back)
				(layer "Inner"
					(shape circle)
					(size 1.397 1.397)
					(clearance 0.0508)
				)
				(layer "B.Cu"
					(shape rect)
					(size 1.397 1.397)
					(clearance 0.0508)
				)
			)
		)
		(pad "2" thru_hole circle
			(at 1.27 -2.54)
			(size 1.397 1.397)
			(drill 0.9906)
			(layers "*.Cu" "*.Mask")
			(remove_unused_layers no)
			(net "UART_DSR_RP6_L")
			(clearance 0.0508)
			(thermal_gap 0.0508)
		)
		(pad "3" thru_hole circle
			(at 2.54 0)
			(size 1.397 1.397)
			(drill 0.9906)
			(layers "*.Cu" "*.Mask")
			(remove_unused_layers no)
			(net "UART_RX_RP6_L")
			(clearance 0.0508)
			(thermal_gap 0.0508)
		)
		(pad "4" thru_hole circle
			(at 3.81 -2.54)
			(size 1.397 1.397)
			(drill 0.9906)
			(layers "*.Cu" "*.Mask")
			(remove_unused_layers no)
			(net "UART_RI_RP6_L_N")
			(clearance 0.0508)
			(thermal_gap 0.0508)
		)
		(pad "5" thru_hole circle
			(at 5.08 0)
			(size 1.397 1.397)
			(drill 0.9906)
			(layers "*.Cu" "*.Mask")
			(remove_unused_layers no)
			(net "GND")
			(clearance 0.0508)
			(thermal_gap 0.0508)
		)
		(pad "6" thru_hole circle
			(at 6.35 -2.54)
			(size 1.397 1.397)
			(drill 0.9906)
			(layers "*.Cu" "*.Mask")
			(remove_unused_layers no)
			(net "UART_TX_RP6_L")
			(clearance 0.0508)
			(thermal_gap 0.0508)
		)
		(pad "7" thru_hole circle
			(at 7.62 0)
			(size 1.397 1.397)
			(drill 0.9906)
			(layers "*.Cu" "*.Mask")
			(remove_unused_layers no)
			(net "UART_DTR_RP6_L_N")
			(clearance 0.0508)
			(thermal_gap 0.0508)
		)
		(pad "8" thru_hole circle
			(at 8.89 -2.54)
			(size 1.397 1.397)
			(drill 0.9906)
			(layers "*.Cu" "*.Mask")
			(remove_unused_layers no)
			(net "UART_CTS_RP6_L_N")
			(clearance 0.0508)
			(thermal_gap 0.0508)
		)
		(zone
			(layers "F.Cu" "B.Cu" "In1.Cu" "In2.Cu" "In3.Cu" "In4.Cu" "In5.Cu" "In6.Cu")
			(hatch none 0.5)
			(connect_pads
				(clearance 0)
			)
			(min_thickness 0.25)
			(keepout
				(tracks not_allowed)
				(vias allowed)
				(pads allowed)
				(copperpour not_allowed)
				(footprints allowed)
			)
			(placement
				(enabled no)
				(sheetname "")
			)
			(fill
				(thermal_gap 0.5)
				(thermal_bridge_width 0.5)
				(island_removal_mode 0)
			)
			(polygon
				(pts
					(arc
						(start 5.31749 -514.771894)
						(mid 1.15189 -514.771894)
						(end 5.31749 -514.771894)
					)
				)
			)
		)
		(zone
			(layers "F.Cu" "B.Cu" "In1.Cu" "In2.Cu" "In3.Cu" "In4.Cu" "In5.Cu" "In6.Cu")
			(hatch none 0.5)
			(connect_pads
				(clearance 0)
			)
			(min_thickness 0.25)
			(keepout
				(tracks not_allowed)
				(vias allowed)
				(pads allowed)
				(copperpour not_allowed)
				(footprints allowed)
			)
			(placement
				(enabled no)
				(sheetname "")
			)
			(fill
				(thermal_gap 0.5)
				(thermal_bridge_width 0.5)
				(island_removal_mode 0)
			)
			(polygon
				(pts
					(arc
						(start 16.74749 -514.771894)
						(mid 12.58189 -514.771894)
						(end 16.74749 -514.771894)
					)
				)
			)
		)
	)
	(footprint ""
		(layer "F.Cu")
		(at 46.36516 -256.467102 180)
		(property "Reference" "R108"
			(at -1.033272 -0.247396 0)
			(unlocked yes)
			(layer "F.SilkS")
			(effects
				(font
					(size 0.7874 0.5842)
					(thickness 0.1524)
				)
				(justify left)
			)
		)
		(property "Value" ""
			(at 0 0 180)
			(layer "F.Fab")
			(effects
				(font
					(size 1.27 1.27)
				)
			)
		)
		(duplicate_pad_numbers_are_jumpers no)
		(fp_line
			(start 0.7874 0.4064)
			(end -0.7874 0.4064)
			(stroke
				(width 0.1524)
				(type default)
			)
			(layer "F.SilkS")
		)
		(fp_line
			(start 0.7874 -0.4064)
			(end 0.7874 0.4064)
			(stroke
				(width 0.1524)
				(type default)
			)
			(layer "F.SilkS")
		)
		(fp_line
			(start -0.7874 0.4064)
			(end -0.7874 -0.4064)
			(stroke
				(width 0.1524)
				(type default)
			)
			(layer "F.SilkS")
		)
		(fp_line
			(start -0.7874 -0.4064)
			(end 0.7874 -0.4064)
			(stroke
				(width 0.1524)
				(type default)
			)
			(layer "F.SilkS")
		)
		(fp_poly
			(pts
				(xy -0.508 0.2794) (xy -0.508 0.2286) (xy -0.635 0.2286) (xy -0.635 -0.254) (xy -0.5334 -0.254)
				(xy -0.5334 -0.2794) (xy 0.5334 -0.2794) (xy 0.5334 -0.254) (xy 0.635 -0.254) (xy 0.635 0.254) (xy 0.5334 0.254)
				(xy 0.5334 0.2794)
			)
			(stroke
				(width 0)
				(type default)
			)
			(fill no)
			(layer "F.CrtYd")
		)
		(pad "1" smd rect
			(at 0.40005 0 180)
			(size 0.4572 0.508)
			(layers "F.Cu" "F.Mask" "F.Paste")
			(net "PSU4_REMOTE_R_P")
		)
		(pad "2" smd rect
			(at -0.40005 0 180)
			(size 0.4572 0.508)
			(layers "F.Cu" "F.Mask" "F.Paste")
			(net "P12V")
		)
	)
	(footprint ""
		(layer "F.Cu")
		(at 72.559164 -263.260078 90)
		(property "Reference" "C48"
			(at -4.374134 -0.046482 90)
			(unlocked yes)
			(layer "F.SilkS")
			(effects
				(font
					(size 0.7874 0.5842)
					(thickness 0.1524)
				)
				(justify left)
			)
		)
		(property "Value" ""
			(at 0 0 90)
			(layer "F.Fab")
			(effects
				(font
					(size 1.27 1.27)
				)
			)
		)
		(duplicate_pad_numbers_are_jumpers no)
		(fp_line
			(start 0.7874 -0.4064)
			(end 0.7874 0.4064)
			(stroke
				(width 0.1524)
				(type default)
			)
			(layer "F.SilkS")
		)
		(fp_line
			(start -0.7874 -0.4064)
			(end 0.7874 -0.4064)
			(stroke
				(width 0.1524)
				(type default)
			)
			(layer "F.SilkS")
		)
		(fp_line
			(start 0 0.381)
			(end 0 -0.381)
			(stroke
				(width 0.1524)
				(type default)
			)
			(layer "F.SilkS")
		)
		(fp_line
			(start 0.7874 0.4064)
			(end -0.7874 0.4064)
			(stroke
				(width 0.1524)
				(type default)
			)
			(layer "F.SilkS")
		)
		(fp_line
			(start -0.7874 0.4064)
			(end -0.7874 -0.4064)
			(stroke
				(width 0.1524)
				(type default)
			)
			(layer "F.SilkS")
		)
		(fp_poly
			(pts
				(xy -0.5334 0.254) (xy -0.635 0.254) (xy -0.635 0.2286) (xy -0.635 -0.254) (xy -0.5334 -0.254) (xy -0.5334 -0.2794)
				(xy 0.5334 -0.2794) (xy 0.5334 -0.254) (xy 0.635 -0.254) (xy 0.635 0.254) (xy 0.5334 0.254) (xy 0.5334 0.2794)
				(xy -0.508 0.2794) (xy -0.5334 0.2794)
			)
			(stroke
				(width 0)
				(type default)
			)
			(fill no)
			(layer "F.CrtYd")
		)
		(pad "1" smd rect
			(at 0.40005 0 90)
			(size 0.4572 0.508)
			(layers "F.Cu" "F.Mask" "F.Paste")
			(net "P12V")
		)
		(pad "2" smd rect
			(at -0.40005 0 90)
			(size 0.4572 0.508)
			(layers "F.Cu" "F.Mask" "F.Paste")
			(net "GND")
		)
	)
	(footprint ""
		(layer "F.Cu")
		(at 27.577796 -373.032528 90)
		(property "Reference" "R129"
			(at -3.094482 -0.932942 90)
			(unlocked yes)
			(layer "F.SilkS")
			(effects
				(font
					(size 0.7874 0.5842)
					(thickness 0.1524)
				)
				(justify left)
			)
		)
		(property "Value" ""
			(at 0 0 90)
			(layer "F.Fab")
			(effects
				(font
					(size 1.27 1.27)
				)
			)
		)
		(duplicate_pad_numbers_are_jumpers no)
		(fp_line
			(start 0.7874 -0.4064)
			(end 0.7874 0.4064)
			(stroke
				(width 0.1524)
				(type default)
			)
			(layer "F.SilkS")
		)
		(fp_line
			(start -0.7874 -0.4064)
			(end 0.7874 -0.4064)
			(stroke
				(width 0.1524)
				(type default)
			)
			(layer "F.SilkS")
		)
		(fp_line
			(start 0.7874 0.4064)
			(end -0.7874 0.4064)
			(stroke
				(width 0.1524)
				(type default)
			)
			(layer "F.SilkS")
		)
		(fp_line
			(start -0.7874 0.4064)
			(end -0.7874 -0.4064)
			(stroke
				(width 0.1524)
				(type default)
			)
			(layer "F.SilkS")
		)
		(fp_poly
			(pts
				(xy -0.508 0.2794) (xy -0.508 0.2286) (xy -0.635 0.2286) (xy -0.635 -0.254) (xy -0.5334 -0.254)
				(xy -0.5334 -0.2794) (xy 0.5334 -0.2794) (xy 0.5334 -0.254) (xy 0.635 -0.254) (xy 0.635 0.254) (xy 0.5334 0.254)
				(xy 0.5334 0.2794)
			)
			(stroke
				(width 0)
				(type default)
			)
			(fill no)
			(layer "F.CrtYd")
		)
		(pad "1" smd rect
			(at 0.40005 0 90)
			(size 0.4572 0.508)
			(layers "F.Cu" "F.Mask" "F.Paste")
			(net "PSU5_REMOTE_N")
		)
		(pad "2" smd rect
			(at -0.40005 0 90)
			(size 0.4572 0.508)
			(layers "F.Cu" "F.Mask" "F.Paste")
			(net "PSU5_REMOTE_R2_N")
		)
	)
	(footprint ""
		(layer "F.Cu")
		(at 78.397354 -14.939772 -90)
		(property "Reference" "C4"
			(at -1.75133 0.035052 90)
			(unlocked yes)
			(layer "F.SilkS")
			(effects
				(font
					(size 0.7874 0.5842)
					(thickness 0.1524)
				)
				(justify left)
			)
		)
		(property "Value" ""
			(at 0 0 270)
			(layer "F.Fab")
			(effects
				(font
					(size 1.27 1.27)
				)
			)
		)
		(duplicate_pad_numbers_are_jumpers no)
		(fp_line
			(start -0.7874 0.4064)
			(end -0.7874 -0.4064)
			(stroke
				(width 0.1524)
				(type default)
			)
			(layer "F.SilkS")
		)
		(fp_line
			(start 0.7874 0.4064)
			(end -0.7874 0.4064)
			(stroke
				(width 0.1524)
				(type default)
			)
			(layer "F.SilkS")
		)
		(fp_line
			(start 0 0.381)
			(end 0 -0.381)
			(stroke
				(width 0.1524)
				(type default)
			)
			(layer "F.SilkS")
		)
		(fp_line
			(start -0.7874 -0.4064)
			(end 0.7874 -0.4064)
			(stroke
				(width 0.1524)
				(type default)
			)
			(layer "F.SilkS")
		)
		(fp_line
			(start 0.7874 -0.4064)
			(end 0.7874 0.4064)
			(stroke
				(width 0.1524)
				(type default)
			)
			(layer "F.SilkS")
		)
		(fp_poly
			(pts
				(xy -0.5334 0.254) (xy -0.635 0.254) (xy -0.635 0.2286) (xy -0.635 -0.254) (xy -0.5334 -0.254) (xy -0.5334 -0.2794)
				(xy 0.5334 -0.2794) (xy 0.5334 -0.254) (xy 0.635 -0.254) (xy 0.635 0.254) (xy 0.5334 0.254) (xy 0.5334 0.2794)
				(xy -0.508 0.2794) (xy -0.5334 0.2794)
			)
			(stroke
				(width 0)
				(type default)
			)
			(fill no)
			(layer "F.CrtYd")
		)
		(pad "1" smd rect
			(at 0.40005 0 270)
			(size 0.4572 0.508)
			(layers "F.Cu" "F.Mask" "F.Paste")
			(net "P12V")
		)
		(pad "2" smd rect
			(at -0.40005 0 270)
			(size 0.4572 0.508)
			(layers "F.Cu" "F.Mask" "F.Paste")
			(net "GND")
		)
	)
	(footprint ""
		(layer "F.Cu")
		(at 39.873936 -462.37144)
		(property "Reference" "R18"
			(at 1.141984 0.133096 0)
			(unlocked yes)
			(layer "F.SilkS")
			(effects
				(font
					(size 0.7874 0.5842)
					(thickness 0.1524)
				)
				(justify left)
			)
		)
		(property "Value" ""
			(at 0 0 0)
			(layer "F.Fab")
			(effects
				(font
					(size 1.27 1.27)
				)
			)
		)
		(duplicate_pad_numbers_are_jumpers no)
		(fp_line
			(start -0.7874 -0.4064)
			(end 0.7874 -0.4064)
			(stroke
				(width 0.1524)
				(type default)
			)
			(layer "F.SilkS")
		)
		(fp_line
			(start -0.7874 0.4064)
			(end -0.7874 -0.4064)
			(stroke
				(width 0.1524)
				(type default)
			)
			(layer "F.SilkS")
		)
		(fp_line
			(start 0.7874 -0.4064)
			(end 0.7874 0.4064)
			(stroke
				(width 0.1524)
				(type default)
			)
			(layer "F.SilkS")
		)
		(fp_line
			(start 0.7874 0.4064)
			(end -0.7874 0.4064)
			(stroke
				(width 0.1524)
				(type default)
			)
			(layer "F.SilkS")
		)
		(fp_poly
			(pts
				(xy -0.508 0.2794) (xy -0.508 0.2286) (xy -0.635 0.2286) (xy -0.635 -0.254) (xy -0.5334 -0.254)
				(xy -0.5334 -0.2794) (xy 0.5334 -0.2794) (xy 0.5334 -0.254) (xy 0.635 -0.254) (xy 0.635 0.254) (xy 0.5334 0.254)
				(xy 0.5334 0.2794)
			)
			(stroke
				(width 0)
				(type default)
			)
			(fill no)
			(layer "F.CrtYd")
		)
		(pad "1" smd rect
			(at 0.40005 0)
			(size 0.4572 0.508)
			(layers "F.Cu" "F.Mask" "F.Paste")
			(net "PSU6_AD0")
		)
		(pad "2" smd rect
			(at -0.40005 0)
			(size 0.4572 0.508)
			(layers "F.Cu" "F.Mask" "F.Paste")
			(net "P12V_STBY")
		)
	)
)
